(kicad_pcb
	(version 20260206)
	(generator "pcbnew")
	(generator_version "10.0")
	(general
		(thickness 1.6)
		(legacy_teardrops no)
	)
	(paper "A4")
	(title_block
		(title "fcb — Lightning_FCB_BRD.brd")
		(comment 1 "Lightning (Wiwynn / Facebook NVMe JBOF) / footprints 426-430 of 495")
	)
	(layers
		(0 "F.Cu" signal "TOP")
		(4 "In1.Cu" signal "L2GND")
		(6 "In2.Cu" signal "L3VCC")
		(2 "B.Cu" signal "BOTTOM")
		(9 "F.Adhes" user "F.Adhesive")
		(11 "B.Adhes" user "B.Adhesive")
		(13 "F.Paste" user "Package Geometry/Pastemask Top")
		(15 "B.Paste" user "Package Geometry/Pastemask Bottom")
		(5 "F.SilkS" user "Ref Des/Silkscreen Top")
		(7 "B.SilkS" user "Ref Des/Silkscreen Bottom")
		(1 "F.Mask" user "Board Geometry/Soldermask Top")
		(3 "B.Mask" user "Board Geometry/Soldermask Bottom")
		(17 "Dwgs.User" user "User.Drawings")
		(19 "Cmts.User" user "User.Comments")
		(21 "Eco1.User" user "User.Eco1")
		(23 "Eco2.User" user "User.Eco2")
		(25 "Edge.Cuts" user "Board Geometry/Outline")
		(27 "Margin" user)
		(31 "F.CrtYd" user "Package Geometry/Place Bound Top")
		(29 "B.CrtYd" user "Package Geometry/Place Bound Bottom")
		(35 "F.Fab" user "Ref Des/Assembly Top")
		(33 "B.Fab" user "Ref Des/Assembly Bottom")
	)
	(footprint ""
		(layer "F.Cu")
		(at 28.2448 -210.8454 180)
		(property "Reference" "R137"
			(at 0 0 180)
			(layer "F.SilkS")
			(hide yes)
			(effects
				(font
					(size 1.27 1.27)
				)
			)
		)
		(property "Value" "0R2J-2-GP"
			(at 0.064008 -3.993896 180)
			(unlocked yes)
			(layer "F.Fab")
			(hide yes)
			(effects
				(font
					(size 1.016 1.016)
					(thickness 0.1524)
				)
			)
		)
		(property "Device Type" "R402H16"
			(at 0.064008 -5.517896 180)
			(unlocked yes)
			(layer "F.Fab")
			(hide yes)
			(effects
				(font
					(size 1.016 1.016)
					(thickness 0.1524)
				)
			)
		)
		(duplicate_pad_numbers_are_jumpers no)
		(fp_line
			(start 0.508 -0.9398)
			(end -0.508 -0.9398)
			(stroke
				(width 0.1524)
				(type default)
			)
			(layer "F.SilkS")
		)
		(fp_line
			(start -0.508 -0.9398)
			(end -0.508 0.9398)
			(stroke
				(width 0.1524)
				(type default)
			)
			(layer "F.SilkS")
		)
		(fp_rect
			(start -0.508 0.9398)
			(end 0.508 -0.9398)
			(stroke
				(width 0)
				(type default)
			)
			(fill no)
			(layer "F.CrtYd")
		)
		(fp_rect
			(start -0.508 0.9398)
			(end 0.508 -0.9398)
			(stroke
				(width 0)
				(type default)
			)
			(fill no)
			(layer "F.Fab")
		)
		(pad "1" smd custom
			(at 0 -0.4445 180)
			(size 0.1397 0.1397)
			(layers "F.Cu" "F.Mask" "F.Paste")
			(net "PWM_OUT_FAN5_NET")
			(options
				(clearance outline)
				(anchor circle)
			)
			(primitives
				(gr_poly
					(pts
						(arc
							(start -0.1778 -0.2794)
							(mid -0.249642 -0.249642)
							(end -0.2794 -0.1778)
						)
						(arc
							(start -0.2794 0.1778)
							(mid -0.249642 0.249642)
							(end -0.1778 0.2794)
						)
						(arc
							(start 0.1778 0.2794)
							(mid 0.249642 0.249642)
							(end 0.2794 0.1778)
						)
						(arc
							(start 0.2794 -0.1778)
							(mid 0.249642 -0.249642)
							(end 0.1778 -0.2794)
						)
					)
					(width 0)
					(fill yes)
				)
			)
		)
		(pad "2" smd custom
			(at 0 0.4445 180)
			(size 0.1397 0.1397)
			(layers "F.Cu" "F.Mask" "F.Paste")
			(net "PWM_OUT_FAN5")
			(options
				(clearance outline)
				(anchor circle)
			)
			(primitives
				(gr_poly
					(pts
						(arc
							(start -0.1778 -0.2794)
							(mid -0.249642 -0.249642)
							(end -0.2794 -0.1778)
						)
						(arc
							(start -0.2794 0.1778)
							(mid -0.249642 0.249642)
							(end -0.1778 0.2794)
						)
						(arc
							(start 0.1778 0.2794)
							(mid 0.249642 0.249642)
							(end 0.2794 0.1778)
						)
						(arc
							(start 0.2794 -0.1778)
							(mid 0.249642 -0.249642)
							(end 0.1778 -0.2794)
						)
					)
					(width 0)
					(fill yes)
				)
			)
		)
	)
	(footprint ""
		(layer "F.Cu")
		(at 12.7 -447.1162 90)
		(property "Reference" "C46"
			(at 0 0 90)
			(layer "F.SilkS")
			(hide yes)
			(effects
				(font
					(size 1.27 1.27)
				)
			)
		)
		(property "Value" "SCD1U16V2KX-3GP"
			(at 1.1811 -2.7051 90)
			(unlocked yes)
			(layer "F.Fab")
			(hide yes)
			(effects
				(font
					(size 1.016 1.016)
					(thickness 0.1524)
				)
			)
		)
		(property "Device Type" "C402H22"
			(at 1.1811 -4.2291 90)
			(unlocked yes)
			(layer "F.Fab")
			(hide yes)
			(effects
				(font
					(size 1.016 1.016)
					(thickness 0.1524)
				)
			)
		)
		(duplicate_pad_numbers_are_jumpers no)
		(fp_rect
			(start -0.4318 0.9525)
			(end 0.4318 -0.9525)
			(stroke
				(width 0)
				(type default)
			)
			(fill no)
			(layer "F.CrtYd")
		)
		(fp_rect
			(start -0.4318 0.9525)
			(end 0.4318 -0.9525)
			(stroke
				(width 0)
				(type default)
			)
			(fill no)
			(layer "F.Fab")
		)
		(pad "1" smd custom
			(at 0 -0.4445 90)
			(size 0.1524 0.1524)
			(layers "F.Cu" "F.Mask" "F.Paste")
			(net "FAN_TACH2")
			(options
				(clearance outline)
				(anchor circle)
			)
			(primitives
				(gr_poly
					(pts
						(arc
							(start 0.3048 -0.2032)
							(mid 0.275042 -0.275042)
							(end 0.2032 -0.3048)
						)
						(arc
							(start -0.2032 -0.3048)
							(mid -0.275042 -0.275042)
							(end -0.3048 -0.2032)
						)
						(arc
							(start -0.3048 0.2032)
							(mid -0.275042 0.275042)
							(end -0.2032 0.3048)
						)
						(arc
							(start 0.2032 0.3048)
							(mid 0.275042 0.275042)
							(end 0.3048 0.2032)
						)
					)
					(width 0)
					(fill yes)
				)
			)
		)
		(pad "2" smd custom
			(at 0 0.4445 90)
			(size 0.1524 0.1524)
			(layers "F.Cu" "F.Mask" "F.Paste")
			(net "GND")
			(options
				(clearance outline)
				(anchor circle)
			)
			(primitives
				(gr_poly
					(pts
						(arc
							(start 0.3048 -0.2032)
							(mid 0.275042 -0.275042)
							(end 0.2032 -0.3048)
						)
						(arc
							(start -0.2032 -0.3048)
							(mid -0.275042 -0.275042)
							(end -0.3048 -0.2032)
						)
						(arc
							(start -0.3048 0.2032)
							(mid -0.275042 0.275042)
							(end -0.2032 0.3048)
						)
						(arc
							(start 0.2032 0.3048)
							(mid 0.275042 0.275042)
							(end 0.3048 0.2032)
						)
					)
					(width 0)
					(fill yes)
				)
			)
		)
	)
	(footprint ""
		(layer "F.Cu")
		(at 22.537166 -135.554466 -90)
		(property "Reference" "PR98"
			(at 0 0 270)
			(layer "F.SilkS")
			(hide yes)
			(effects
				(font
					(size 1.27 1.27)
				)
			)
		)
		(property "Value" "1MR3J-L-GP"
			(at -0.0254 -2.5146 270)
			(unlocked yes)
			(layer "F.Fab")
			(hide yes)
			(effects
				(font
					(size 1.016 1.016)
					(thickness 0.1524)
				)
			)
		)
		(property "Device Type" "R603H22"
			(at -0.0254 -4.0386 270)
			(unlocked yes)
			(layer "F.Fab")
			(hide yes)
			(effects
				(font
					(size 1.016 1.016)
					(thickness 0.1524)
				)
			)
		)
		(duplicate_pad_numbers_are_jumpers no)
		(fp_line
			(start -0.4826 0)
			(end -0.2032 0)
			(stroke
				(width 0.2032)
				(type default)
			)
			(layer "F.SilkS")
		)
		(fp_line
			(start 0.2032 0)
			(end 0.4826 0)
			(stroke
				(width 0.2032)
				(type default)
			)
			(layer "F.SilkS")
		)
		(fp_rect
			(start -0.5842 1.3335)
			(end 0.5842 -1.3335)
			(stroke
				(width 0)
				(type default)
			)
			(fill no)
			(layer "F.CrtYd")
		)
		(fp_rect
			(start -0.5842 1.3335)
			(end 0.5842 -1.3335)
			(stroke
				(width 0)
				(type default)
			)
			(fill no)
			(layer "F.Fab")
		)
		(pad "1" smd custom
			(at 0 -0.762 270)
			(size 0.2159 0.2159)
			(layers "F.Cu" "F.Mask" "F.Paste")
			(net "P12VU_2490_VCC")
			(options
				(clearance outline)
				(anchor circle)
			)
			(primitives
				(gr_poly
					(pts
						(arc
							(start -0.3302 -0.4318)
							(mid -0.402042 -0.402042)
							(end -0.4318 -0.3302)
						)
						(arc
							(start -0.4318 0.3302)
							(mid -0.402042 0.402042)
							(end -0.3302 0.4318)
						)
						(arc
							(start 0.3302 0.4318)
							(mid 0.402042 0.402042)
							(end 0.4318 0.3302)
						)
						(arc
							(start 0.4318 -0.3302)
							(mid 0.402042 -0.402042)
							(end 0.3302 -0.4318)
						)
					)
					(width 0)
					(fill yes)
				)
			)
		)
		(pad "2" smd custom
			(at 0 0.762 270)
			(size 0.2159 0.2159)
			(layers "F.Cu" "F.Mask" "F.Paste")
			(net "P12VU_2490_SENSE")
			(options
				(clearance outline)
				(anchor circle)
			)
			(primitives
				(gr_poly
					(pts
						(arc
							(start -0.3302 -0.4318)
							(mid -0.402042 -0.402042)
							(end -0.4318 -0.3302)
						)
						(arc
							(start -0.4318 0.3302)
							(mid -0.402042 0.402042)
							(end -0.3302 0.4318)
						)
						(arc
							(start 0.3302 0.4318)
							(mid 0.402042 0.402042)
							(end 0.4318 0.3302)
						)
						(arc
							(start 0.4318 -0.3302)
							(mid 0.402042 -0.402042)
							(end 0.3302 -0.4318)
						)
					)
					(width 0)
					(fill yes)
				)
			)
		)
	)
	(footprint ""
		(layer "F.Cu")
		(at 26.416 -374.523 -90)
		(property "Reference" "PC1"
			(at 0 0 270)
			(layer "F.SilkS")
			(hide yes)
			(effects
				(font
					(size 1.27 1.27)
				)
			)
		)
		(property "Value" "SC1U25V3KX-1-GP"
			(at 0 -2.8194 270)
			(unlocked yes)
			(layer "F.Fab")
			(hide yes)
			(effects
				(font
					(size 1.016 1.016)
					(thickness 0.1524)
				)
			)
		)
		(property "Device Type" "C603H36"
			(at 0 -4.3434 270)
			(unlocked yes)
			(layer "F.Fab")
			(hide yes)
			(effects
				(font
					(size 1.016 1.016)
					(thickness 0.1524)
				)
			)
		)
		(duplicate_pad_numbers_are_jumpers no)
		(fp_line
			(start 0.508 0)
			(end -0.508 0)
			(stroke
				(width 0.2032)
				(type default)
			)
			(layer "F.SilkS")
		)
		(fp_rect
			(start -0.5842 1.3335)
			(end 0.5842 -1.3335)
			(stroke
				(width 0)
				(type default)
			)
			(fill no)
			(layer "F.CrtYd")
		)
		(fp_rect
			(start -0.5842 1.3335)
			(end 0.5842 -1.3335)
			(stroke
				(width 0)
				(type default)
			)
			(fill no)
			(layer "F.Fab")
		)
		(pad "1" smd custom
			(at 0 -0.762 270)
			(size 0.2159 0.2159)
			(layers "F.Cu" "F.Mask" "F.Paste")
			(net "ADM1276_VCC")
			(options
				(clearance outline)
				(anchor circle)
			)
			(primitives
				(gr_poly
					(pts
						(arc
							(start -0.3302 -0.4318)
							(mid -0.402042 -0.402042)
							(end -0.4318 -0.3302)
						)
						(arc
							(start -0.4318 0.3302)
							(mid -0.402042 0.402042)
							(end -0.3302 0.4318)
						)
						(arc
							(start 0.3302 0.4318)
							(mid 0.402042 0.402042)
							(end 0.4318 0.3302)
						)
						(arc
							(start 0.4318 -0.3302)
							(mid 0.402042 -0.402042)
							(end 0.3302 -0.4318)
						)
					)
					(width 0)
					(fill yes)
				)
			)
		)
		(pad "2" smd custom
			(at 0 0.762 270)
			(size 0.2159 0.2159)
			(layers "F.Cu" "F.Mask" "F.Paste")
			(net "GND")
			(options
				(clearance outline)
				(anchor circle)
			)
			(primitives
				(gr_poly
					(pts
						(arc
							(start -0.3302 -0.4318)
							(mid -0.402042 -0.402042)
							(end -0.4318 -0.3302)
						)
						(arc
							(start -0.4318 0.3302)
							(mid -0.402042 0.402042)
							(end -0.3302 0.4318)
						)
						(arc
							(start 0.3302 0.4318)
							(mid 0.402042 0.402042)
							(end 0.4318 0.3302)
						)
						(arc
							(start 0.4318 -0.3302)
							(mid 0.402042 -0.402042)
							(end 0.3302 -0.4318)
						)
					)
					(width 0)
					(fill yes)
				)
			)
		)
	)
	(footprint ""
		(layer "F.Cu")
		(at 36.212526 -362.208826)
		(property "Reference" "PQ5"
			(at 0 0 0)
			(layer "F.SilkS")
			(hide yes)
			(effects
				(font
					(size 1.27 1.27)
				)
			)
		)
		(property "Value" "PMBS3904-1-GP"
			(at 0 -9.0932 0)
			(unlocked yes)
			(layer "F.Fab")
			(hide yes)
			(effects
				(font
					(size 1.016 1.016)
					(thickness 0.1524)
				)
			)
		)
		(property "Device Type" "SOT-23-10H44"
			(at 0 -10.6172 0)
			(unlocked yes)
			(layer "F.Fab")
			(hide yes)
			(effects
				(font
					(size 1.016 1.016)
					(thickness 0.1524)
				)
			)
		)
		(duplicate_pad_numbers_are_jumpers no)
		(fp_line
			(start -1.7526 1.8796)
			(end -1.7526 0.9906)
			(stroke
				(width 0.3302)
				(type default)
			)
			(layer "F.SilkS")
		)
		(fp_line
			(start -1.651 -1.778)
			(end -1.651 1.778)
			(stroke
				(width 0.1524)
				(type default)
			)
			(layer "F.SilkS")
		)
		(fp_line
			(start -1.651 1.778)
			(end 1.651 1.778)
			(stroke
				(width 0.1524)
				(type default)
			)
			(layer "F.SilkS")
		)
		(fp_line
			(start -1.279398 2.152142)
			(end -0.9906 1.86309)
			(stroke
				(width 0.0127)
				(type default)
			)
			(layer "F.SilkS")
		)
		(fp_line
			(start -1.279144 2.15265)
			(end -0.701294 2.15265)
			(stroke
				(width 0.0127)
				(type default)
			)
			(layer "F.SilkS")
		)
		(fp_line
			(start -1.260856 2.1336)
			(end -0.720344 2.1336)
			(stroke
				(width 0.0127)
				(type default)
			)
			(layer "F.SilkS")
		)
		(fp_line
			(start -1.251458 2.124202)
			(end -0.729996 2.124202)
			(stroke
				(width 0.0127)
				(type default)
			)
			(layer "F.SilkS")
		)
		(fp_line
			(start -1.241806 2.11455)
			(end -0.739394 2.11455)
			(stroke
				(width 0.0127)
				(type default)
			)
			(layer "F.SilkS")
		)
		(fp_line
			(start -1.232408 2.105152)
			(end -0.749046 2.105152)
			(stroke
				(width 0.0127)
				(type default)
			)
			(layer "F.SilkS")
		)
		(fp_line
			(start -1.222756 2.0955)
			(end -0.758444 2.0955)
			(stroke
				(width 0.0127)
				(type default)
			)
			(layer "F.SilkS")
		)
		(fp_line
			(start -1.213358 2.086102)
			(end -0.768096 2.086102)
			(stroke
				(width 0.0127)
				(type default)
			)
			(layer "F.SilkS")
		)
		(fp_line
			(start -1.203706 2.07645)
			(end -0.777494 2.07645)
			(stroke
				(width 0.0127)
				(type default)
			)
			(layer "F.SilkS")
		)
		(fp_line
			(start -1.194308 2.067052)
			(end -0.787146 2.067052)
			(stroke
				(width 0.0127)
				(type default)
			)
			(layer "F.SilkS")
		)
		(fp_line
			(start -1.184656 2.0574)
			(end -0.796544 2.0574)
			(stroke
				(width 0.0127)
				(type default)
			)
			(layer "F.SilkS")
		)
		(fp_line
			(start -1.175258 2.048002)
			(end -0.806196 2.048002)
			(stroke
				(width 0.0127)
				(type default)
			)
			(layer "F.SilkS")
		)
		(fp_line
			(start -1.165606 2.03835)
			(end -0.815594 2.03835)
			(stroke
				(width 0.0127)
				(type default)
			)
			(layer "F.SilkS")
		)
		(fp_line
			(start -1.156208 2.028952)
			(end -0.825246 2.028952)
			(stroke
				(width 0.0127)
				(type default)
			)
			(layer "F.SilkS")
		)
		(fp_line
			(start -1.146556 2.0193)
			(end -0.834644 2.0193)
			(stroke
				(width 0.0127)
				(type default)
			)
			(layer "F.SilkS")
		)
		(fp_line
			(start -1.137158 2.009902)
			(end -0.844296 2.009902)
			(stroke
				(width 0.0127)
				(type default)
			)
			(layer "F.SilkS")
		)
		(fp_line
			(start -1.127506 2.00025)
			(end -0.853694 2.00025)
			(stroke
				(width 0.0127)
				(type default)
			)
			(layer "F.SilkS")
		)
		(fp_line
			(start -1.118108 1.990852)
			(end -0.863346 1.990852)
			(stroke
				(width 0.0127)
				(type default)
			)
			(layer "F.SilkS")
		)
		(fp_line
			(start -1.108456 1.9812)
			(end -0.872744 1.9812)
			(stroke
				(width 0.0127)
				(type default)
			)
			(layer "F.SilkS")
		)
		(fp_line
			(start -1.099058 1.971802)
			(end -0.882396 1.971802)
			(stroke
				(width 0.0127)
				(type default)
			)
			(layer "F.SilkS")
		)
		(fp_line
			(start -1.089406 1.96215)
			(end -0.891794 1.96215)
			(stroke
				(width 0.0127)
				(type default)
			)
			(layer "F.SilkS")
		)
		(fp_line
			(start -1.080008 1.952752)
			(end -0.901446 1.952752)
			(stroke
				(width 0.0127)
				(type default)
			)
			(layer "F.SilkS")
		)
		(fp_line
			(start -1.070356 1.9431)
			(end -0.910844 1.9431)
			(stroke
				(width 0.0127)
				(type default)
			)
			(layer "F.SilkS")
		)
		(fp_line
			(start -1.060958 1.933702)
			(end -0.920496 1.933702)
			(stroke
				(width 0.0127)
				(type default)
			)
			(layer "F.SilkS")
		)
		(fp_line
			(start -1.051306 1.92405)
			(end -0.929894 1.92405)
			(stroke
				(width 0.0127)
				(type default)
			)
			(layer "F.SilkS")
		)
		(fp_line
			(start -1.041908 1.914652)
			(end -0.939546 1.914652)
			(stroke
				(width 0.0127)
				(type default)
			)
			(layer "F.SilkS")
		)
		(fp_line
			(start -1.032256 1.905)
			(end -0.948944 1.905)
			(stroke
				(width 0.0127)
				(type default)
			)
			(layer "F.SilkS")
		)
		(fp_line
			(start -1.022858 1.895602)
			(end -0.958596 1.895602)
			(stroke
				(width 0.0127)
				(type default)
			)
			(layer "F.SilkS")
		)
		(fp_line
			(start -1.013206 1.88595)
			(end -0.967994 1.88595)
			(stroke
				(width 0.0127)
				(type default)
			)
			(layer "F.SilkS")
		)
		(fp_line
			(start -1.003808 1.876552)
			(end -0.977646 1.876552)
			(stroke
				(width 0.0127)
				(type default)
			)
			(layer "F.SilkS")
		)
		(fp_line
			(start -0.994156 1.8669)
			(end -0.987044 1.8669)
			(stroke
				(width 0.0127)
				(type default)
			)
			(layer "F.SilkS")
		)
		(fp_line
			(start -0.9906 1.86309)
			(end -0.701294 2.15265)
			(stroke
				(width 0.0127)
				(type default)
			)
			(layer "F.SilkS")
		)
		(fp_line
			(start -0.719074 2.145538)
			(end -1.265936 2.14122)
			(stroke
				(width 0.0127)
				(type default)
			)
			(layer "F.SilkS")
		)
		(fp_line
			(start -0.71628 2.15265)
			(end -1.26492 2.15265)
			(stroke
				(width 0.0127)
				(type default)
			)
			(layer "F.SilkS")
		)
		(fp_line
			(start -0.635 1.8796)
			(end -1.7526 1.8796)
			(stroke
				(width 0.3302)
				(type default)
			)
			(layer "F.SilkS")
		)
		(fp_line
			(start 1.651 -1.778)
			(end -1.651 -1.778)
			(stroke
				(width 0.1524)
				(type default)
			)
			(layer "F.SilkS")
		)
		(fp_line
			(start 1.651 1.778)
			(end 1.651 -1.778)
			(stroke
				(width 0.1524)
				(type default)
			)
			(layer "F.SilkS")
		)
		(fp_poly
			(pts
				(xy -1.285748 2.159) (xy -1.285748 1.8796) (xy -1.778 1.8796) (xy -1.778 -1.8796) (xy 1.778 -1.8796)
				(xy 1.778 1.8796) (xy -0.694944 1.8796) (xy -0.694944 2.159)
			)
			(stroke
				(width 0)
				(type default)
			)
			(fill no)
			(layer "F.CrtYd")
		)
		(fp_poly
			(pts
				(xy -1.285748 2.159) (xy -1.285748 1.8796) (xy -1.778 1.8796) (xy -1.778 -1.8796) (xy 1.778 -1.8796)
				(xy 1.778 1.8796) (xy -0.694944 1.8796) (xy -0.694944 2.159)
			)
			(stroke
				(width 0)
				(type default)
			)
			(fill no)
			(layer "F.Fab")
		)
		(pad "1" smd rect
			(at -0.98425 0.9525)
			(size 0.762 1.143)
			(layers "F.Cu" "F.Mask" "F.Paste")
			(net "TEMP_ALM#_REVERSE_R")
		)
		(pad "2" smd rect
			(at 0.98425 0.9525)
			(size 0.762 1.143)
			(layers "F.Cu" "F.Mask" "F.Paste")
			(net "GND")
		)
		(pad "3" smd rect
			(at 0 -0.9525)
			(size 0.762 1.143)
			(layers "F.Cu" "F.Mask" "F.Paste")
			(net "ADM1276_LATCH_B")
		)
	)
)
